# T6G (Grand Teton) — schematic netlist excerpt (pin names and nets, part order shuffled) for the footprints in the layout excerpt that follows; sources: Cadence DE-HDL packaged netlist, KiCad conversion of 04192023_DAF0TMB3IC0_F0TG_MB_C_brd_V02_OCP.brd

C2514  Q_CAP  22UF 4V 20% X6S  pkg C0402  page 71 : A = PVDD18_S5_P0 ; B = GND
C2387  Q_CAP  22UF 4V 20% X6S  pkg C0402  page 73 : A = PVDDCR_CPU1_P1 ; B = GND

(kicad_pcb
	(version 20260206)
	(generator "pcbnew")
	(generator_version "10.0")
	(general
		(thickness 1.6)
		(legacy_teardrops no)
	)
	(paper "A4")
	(title_block
		(title "04192023_DAF0TMB3IC0_F0TG_MB_C_brd_V02_OCP.brd")
		(comment 1 "Grand Teton / footprints 6521-6522 of 8354")
	)
	(layers
		(0 "F.Cu" signal "TOP")
		(4 "In1.Cu" signal "GND")
		(6 "In2.Cu" signal "IN1")
		(8 "In3.Cu" signal "GND1")
		(10 "In4.Cu" signal "IN2")
		(12 "In5.Cu" signal "GND2")
		(14 "In6.Cu" signal "IN3")
		(16 "In7.Cu" signal "GND3")
		(18 "In8.Cu" signal "VCC")
		(20 "In9.Cu" signal "VCC1")
		(22 "In10.Cu" signal "GND4")
		(24 "In11.Cu" signal "IN4")
		(26 "In12.Cu" signal "GND5")
		(28 "In13.Cu" signal "IN5")
		(30 "In14.Cu" signal "GND6")
		(32 "In15.Cu" signal "IN6")
		(34 "In16.Cu" signal "GND7")
		(2 "B.Cu" signal "BOTTOM")
		(9 "F.Adhes" user "F.Adhesive")
		(11 "B.Adhes" user "B.Adhesive")
		(13 "F.Paste" user "Package Geometry/Pastemask Top")
		(15 "B.Paste" user "Package Geometry/Pastemask Bottom")
		(5 "F.SilkS" user "Ref Des/Silkscreen Top")
		(7 "B.SilkS" user "Ref Des/Silkscreen Bottom")
		(1 "F.Mask" user "Board Geometry/Soldermask Top")
		(3 "B.Mask" user "Board Geometry/Soldermask Bottom")
		(17 "Dwgs.User" user "User.Drawings")
		(19 "Cmts.User" user "User.Comments")
		(21 "Eco1.User" user "User.Eco1")
		(23 "Eco2.User" user "User.Eco2")
		(25 "Edge.Cuts" user "Board Geometry/Outline")
		(27 "Margin" user)
		(31 "F.CrtYd" user "Package Geometry/Place Bound Top")
		(29 "B.CrtYd" user "Package Geometry/Place Bound Bottom")
		(35 "F.Fab" user "Ref Des/Assembly Top")
		(33 "B.Fab" user "Ref Des/Assembly Bottom")
	)
	(footprint ""
		(layer "B.Cu")
		(at 114.467386 -268.418564)
		(property "Reference" "C2387"
			(at 0 0 0)
			(layer "B.SilkS")
			(hide yes)
			(effects
				(font
					(size 1.27 1.27)
				)
				(justify mirror)
			)
		)
		(property "Value" ""
			(at 0 0 0)
			(layer "B.Fab")
			(effects
				(font
					(size 1.27 1.27)
				)
				(justify mirror)
			)
		)
		(duplicate_pad_numbers_are_jumpers no)
		(fp_line
			(start -0.7874 -0.4064)
			(end -0.7874 0.4064)
			(stroke
				(width 0.1524)
				(type default)
			)
			(layer "B.SilkS")
		)
		(fp_line
			(start -0.7874 0.4064)
			(end 0.7874 0.4064)
			(stroke
				(width 0.1524)
				(type default)
			)
			(layer "B.SilkS")
		)
		(fp_line
			(start 0.7874 -0.4064)
			(end -0.7874 -0.4064)
			(stroke
				(width 0.1524)
				(type default)
			)
			(layer "B.SilkS")
		)
		(fp_line
			(start 0.7874 0.4064)
			(end 0.7874 -0.4064)
			(stroke
				(width 0.1524)
				(type default)
			)
			(layer "B.SilkS")
		)
		(fp_line
			(start -0.67945 -0.3048)
			(end -0.67945 0.3048)
			(stroke
				(width 0.1)
				(type default)
			)
			(layer "B.Fab")
		)
		(fp_line
			(start -0.67945 0.3048)
			(end -0.120396 0.3048)
			(stroke
				(width 0.1)
				(type default)
			)
			(layer "B.Fab")
		)
		(fp_line
			(start -0.12065 -0.3048)
			(end -0.67945 -0.3048)
			(stroke
				(width 0.1)
				(type default)
			)
			(layer "B.Fab")
		)
		(fp_line
			(start -0.12065 -0.2794)
			(end -0.12065 -0.3048)
			(stroke
				(width 0.1)
				(type default)
			)
			(layer "B.Fab")
		)
		(fp_line
			(start -0.120396 0.2794)
			(end 0.12065 0.2794)
			(stroke
				(width 0.1)
				(type default)
			)
			(layer "B.Fab")
		)
		(fp_line
			(start -0.120396 0.3048)
			(end -0.120396 0.2794)
			(stroke
				(width 0.1)
				(type default)
			)
			(layer "B.Fab")
		)
		(fp_line
			(start 0.12065 -0.305054)
			(end 0.12065 -0.2794)
			(stroke
				(width 0.1)
				(type default)
			)
			(layer "B.Fab")
		)
		(fp_line
			(start 0.12065 -0.2794)
			(end -0.12065 -0.2794)
			(stroke
				(width 0.1)
				(type default)
			)
			(layer "B.Fab")
		)
		(fp_line
			(start 0.12065 0.2794)
			(end 0.12065 0.3048)
			(stroke
				(width 0.1)
				(type default)
			)
			(layer "B.Fab")
		)
		(fp_line
			(start 0.12065 0.3048)
			(end 0.67945 0.3048)
			(stroke
				(width 0.1)
				(type default)
			)
			(layer "B.Fab")
		)
		(fp_line
			(start 0.67945 -0.305054)
			(end 0.12065 -0.305054)
			(stroke
				(width 0.1)
				(type default)
			)
			(layer "B.Fab")
		)
		(fp_line
			(start 0.67945 0.3048)
			(end 0.67945 -0.305054)
			(stroke
				(width 0.1)
				(type default)
			)
			(layer "B.Fab")
		)
		(pad "1" smd circle
			(at 0.40005 0 180)
			(size 0 0)
			(layers "B.Cu" "B.Mask" "B.Paste")
			(net "PVDDCR_CPU1_P1")
		)
		(pad "2" smd circle
			(at -0.40005 0 180)
			(size 0 0)
			(layers "B.Cu" "B.Mask" "B.Paste")
			(net "GND")
		)
	)
	(footprint ""
		(layer "B.Cu")
		(at 348.913958 -250.89231 180)
		(property "Reference" "C2514"
			(at 0 0 0)
			(layer "B.SilkS")
			(hide yes)
			(effects
				(font
					(size 1.27 1.27)
				)
				(justify mirror)
			)
		)
		(property "Value" ""
			(at 0 0 0)
			(layer "B.Fab")
			(effects
				(font
					(size 1.27 1.27)
				)
				(justify mirror)
			)
		)
		(duplicate_pad_numbers_are_jumpers no)
		(fp_line
			(start 0.7874 0.4064)
			(end 0.7874 -0.4064)
			(stroke
				(width 0.1524)
				(type default)
			)
			(layer "B.SilkS")
		)
		(fp_line
			(start 0.7874 -0.4064)
			(end -0.7874 -0.4064)
			(stroke
				(width 0.1524)
				(type default)
			)
			(layer "B.SilkS")
		)
		(fp_line
			(start -0.7874 0.4064)
			(end 0.7874 0.4064)
			(stroke
				(width 0.1524)
				(type default)
			)
			(layer "B.SilkS")
		)
		(fp_line
			(start -0.7874 -0.4064)
			(end -0.7874 0.4064)
			(stroke
				(width 0.1524)
				(type default)
			)
			(layer "B.SilkS")
		)
		(fp_line
			(start 0.67945 0.3048)
			(end 0.67945 -0.305054)
			(stroke
				(width 0.1)
				(type default)
			)
			(layer "B.Fab")
		)
		(fp_line
			(start 0.67945 -0.305054)
			(end 0.12065 -0.305054)
			(stroke
				(width 0.1)
				(type default)
			)
			(layer "B.Fab")
		)
		(fp_line
			(start 0.12065 0.3048)
			(end 0.67945 0.3048)
			(stroke
				(width 0.1)
				(type default)
			)
			(layer "B.Fab")
		)
		(fp_line
			(start 0.12065 0.2794)
			(end 0.12065 0.3048)
			(stroke
				(width 0.1)
				(type default)
			)
			(layer "B.Fab")
		)
		(fp_line
			(start 0.12065 -0.2794)
			(end -0.12065 -0.2794)
			(stroke
				(width 0.1)
				(type default)
			)
			(layer "B.Fab")
		)
		(fp_line
			(start 0.12065 -0.305054)
			(end 0.12065 -0.2794)
			(stroke
				(width 0.1)
				(type default)
			)
			(layer "B.Fab")
		)
		(fp_line
			(start -0.120396 0.3048)
			(end -0.120396 0.2794)
			(stroke
				(width 0.1)
				(type default)
			)
			(layer "B.Fab")
		)
		(fp_line
			(start -0.120396 0.2794)
			(end 0.12065 0.2794)
			(stroke
				(width 0.1)
				(type default)
			)
			(layer "B.Fab")
		)
		(fp_line
			(start -0.12065 -0.2794)
			(end -0.12065 -0.3048)
			(stroke
				(width 0.1)
				(type default)
			)
			(layer "B.Fab")
		)
		(fp_line
			(start -0.12065 -0.3048)
			(end -0.67945 -0.3048)
			(stroke
				(width 0.1)
				(type default)
			)
			(layer "B.Fab")
		)
		(fp_line
			(start -0.67945 0.3048)
			(end -0.120396 0.3048)
			(stroke
				(width 0.1)
				(type default)
			)
			(layer "B.Fab")
		)
		(fp_line
			(start -0.67945 -0.3048)
			(end -0.67945 0.3048)
			(stroke
				(width 0.1)
				(type default)
			)
			(layer "B.Fab")
		)
		(pad "1" smd circle
			(at 0.40005 0)
			(size 0 0)
			(layers "B.Cu" "B.Mask" "B.Paste")
			(net "PVDD18_S5_P0")
		)
		(pad "2" smd circle
			(at -0.40005 0)
			(size 0 0)
			(layers "B.Cu" "B.Mask" "B.Paste")
			(net "GND")
		)
	)
)
